(kicad_pcb
	(version 20241229)
	(generator "pcbnew")
	(generator_version "9.0")
	(general
		(thickness 1.61)
		(legacy_teardrops no)
	)
	(paper "A3")
	(title_block
		(title "RDIMM DDR5 Tester")
		(date "2026-05-21")
		(rev "2.2.0")
		(company "Antmicro")
		(comment 9 "footprint 109 of 796 (J2), pads 260-291 of 291")
	)
	(layers
		(0 "F.Cu" signal)
		(4 "In1.Cu" power)
		(6 "In2.Cu" mixed)
		(8 "In3.Cu" power)
		(10 "In4.Cu" mixed)
		(12 "In5.Cu" power)
		(14 "In6.Cu" mixed)
		(16 "In7.Cu" power)
		(18 "In8.Cu" power)
		(20 "In9.Cu" mixed)
		(22 "In10.Cu" power)
		(2 "B.Cu" signal)
		(9 "F.Adhes" user "F.Adhesive")
		(11 "B.Adhes" user "B.Adhesive")
		(13 "F.Paste" user)
		(15 "B.Paste" user)
		(5 "F.SilkS" user "F.Silkscreen")
		(7 "B.SilkS" user "B.Silkscreen")
		(1 "F.Mask" user)
		(3 "B.Mask" user)
		(17 "Dwgs.User" user "User.Drawings")
		(19 "Cmts.User" user "User.Comments")
		(21 "Eco1.User" user "User.Eco1")
		(23 "Eco2.User" user "User.Eco2")
		(25 "Edge.Cuts" user)
		(27 "Margin" user)
		(31 "F.CrtYd" user "F.Courtyard")
		(29 "B.CrtYd" user "B.Courtyard")
		(35 "F.Fab" user)
		(33 "B.Fab" user)
	)
	(footprint "antmicro-footprints:Bus_DDR5_Socket_Amphenol_DDR504111002KQ"
		(layer "F.Cu")
		(at 188.325 108.297 180)
		(descr "DIMM Connectors DDR5 SMD 288P")
		(property "Reference" "J2"
			(at 67.825 3.797 0)
			(layer "F.SilkS")
			(effects
				(font
					(size 0.7 0.7)
					(thickness 0.15)
				)
				(justify right bottom)
			)
		)
		(property "Value" "Bus_DDR5_DDR504111002KQ"
			(at 0 4.2 0)
			(layer "F.Fab")
			(effects
				(font
					(size 0.7 0.7)
					(thickness 0.15)
				)
				(justify right bottom)
			)
		)
		(property "Datasheet" "https://www.amphenol-icc.com/ddr5-smt-ddr504111002kq.html"
			(at 0 0 180)
			(layer "F.Fab")
			(hide yes)
			(effects
				(font
					(size 1.27 1.27)
					(thickness 0.15)
				)
			)
		)
		(property "Manufacturer" "Amphenol"
			(at 0 0 180)
			(unlocked yes)
			(layer "F.Fab")
			(hide yes)
			(effects
				(font
					(size 1 1)
					(thickness 0.15)
				)
			)
		)
		(property "MPN" "DDR504111002KQ"
			(at 0 0 180)
			(unlocked yes)
			(layer "F.Fab")
			(hide yes)
			(effects
				(font
					(size 1 1)
					(thickness 0.15)
				)
			)
		)
		(property "Author" "Antmicro"
			(at 0 0 180)
			(unlocked yes)
			(layer "F.Fab")
			(hide yes)
			(effects
				(font
					(size 1 1)
					(thickness 0.15)
				)
			)
		)
		(property "License" "Apache-2.0"
			(at 0 0 180)
			(unlocked yes)
			(layer "F.Fab")
			(hide yes)
			(effects
				(font
					(size 1 1)
					(thickness 0.15)
				)
			)
		)
		(sheetname "/DDR5 RDIMM/")
		(sheetfile "ddr5-rdimm.kicad_sch")
		(attr smd)
		(pad "260" smd rect
			(at 39.524 -2.301 270)
			(size 1.8 0.57)
			(layers "F.Cu" "F.Mask" "F.Paste")
			(net 592 "/DDR5 RDIMM/B.DQS6_N")
			(pinfunction "DQS6_B_C")
			(pintype "input")
		)
		(pad "261" smd rect
			(at 40.374 -2.301 270)
			(size 1.8 0.57)
			(layers "F.Cu" "F.Mask" "F.Paste")
			(net 593 "/DDR5 RDIMM/B.DQS6_P")
			(pinfunction "DQS6_B_T")
			(pintype "input")
		)
		(pad "262" smd rect
			(at 41.225 -2.301 270)
			(size 1.8 0.57)
			(layers "F.Cu" "F.Mask" "F.Paste")
			(net 1 "GND")
			(pinfunction "VSS")
			(pintype "passive")
		)
		(pad "263" smd rect
			(at 42.075 -2.301 270)
			(size 1.8 0.57)
			(layers "F.Cu" "F.Mask" "F.Paste")
			(net 358 "/DDR5 RDIMM/B.DQ14")
			(pinfunction "DQ14_B")
			(pintype "input")
		)
		(pad "264" smd rect
			(at 42.923 -2.301 270)
			(size 1.8 0.57)
			(layers "F.Cu" "F.Mask" "F.Paste")
			(net 1 "GND")
			(pinfunction "VSS")
			(pintype "passive")
		)
		(pad "265" smd rect
			(at 43.773 -2.301 270)
			(size 1.8 0.57)
			(layers "F.Cu" "F.Mask" "F.Paste")
			(net 359 "/DDR5 RDIMM/B.DQ15")
			(pinfunction "DQ15_B")
			(pintype "input")
		)
		(pad "266" smd rect
			(at 44.624 -2.301 270)
			(size 1.8 0.57)
			(layers "F.Cu" "F.Mask" "F.Paste")
			(net 1 "GND")
			(pinfunction "VSS")
			(pintype "passive")
		)
		(pad "267" smd rect
			(at 45.475 -2.301 270)
			(size 1.8 0.57)
			(layers "F.Cu" "F.Mask" "F.Paste")
			(net 360 "/DDR5 RDIMM/B.DQ18")
			(pinfunction "DQ18_B")
			(pintype "input")
		)
		(pad "268" smd rect
			(at 46.325 -2.301 270)
			(size 1.8 0.57)
			(layers "F.Cu" "F.Mask" "F.Paste")
			(net 1 "GND")
			(pinfunction "VSS")
			(pintype "passive")
		)
		(pad "269" smd rect
			(at 47.173 -2.301 270)
			(size 1.8 0.57)
			(layers "F.Cu" "F.Mask" "F.Paste")
			(net 450 "/DDR5 RDIMM/B.DQ19")
			(pinfunction "DQ19_B")
			(pintype "input")
		)
		(pad "270" smd rect
			(at 48.023 -2.301 270)
			(size 1.8 0.57)
			(layers "F.Cu" "F.Mask" "F.Paste")
			(net 1 "GND")
			(pinfunction "VSS")
			(pintype "passive")
		)
		(pad "271" smd rect
			(at 48.874 -2.301 270)
			(size 1.8 0.57)
			(layers "F.Cu" "F.Mask" "F.Paste")
			(net 594 "/DDR5 RDIMM/B.DQS7_N")
			(pinfunction "DQS7_B_C")
			(pintype "input")
		)
		(pad "272" smd rect
			(at 49.725 -2.301 270)
			(size 1.8 0.57)
			(layers "F.Cu" "F.Mask" "F.Paste")
			(net 595 "/DDR5 RDIMM/B.DQS7_P")
			(pinfunction "DQS7_B_T")
			(pintype "input")
		)
		(pad "273" smd rect
			(at 50.575 -2.301 270)
			(size 1.8 0.57)
			(layers "F.Cu" "F.Mask" "F.Paste")
			(net 1 "GND")
			(pinfunction "VSS")
			(pintype "passive")
		)
		(pad "274" smd rect
			(at 51.423 -2.301 270)
			(size 1.8 0.57)
			(layers "F.Cu" "F.Mask" "F.Paste")
			(net 453 "/DDR5 RDIMM/B.DQ22")
			(pinfunction "DQ22_B")
			(pintype "input")
		)
		(pad "275" smd rect
			(at 52.273 -2.301 270)
			(size 1.8 0.57)
			(layers "F.Cu" "F.Mask" "F.Paste")
			(net 1 "GND")
			(pinfunction "VSS")
			(pintype "passive")
		)
		(pad "276" smd rect
			(at 53.124 -2.301 270)
			(size 1.8 0.57)
			(layers "F.Cu" "F.Mask" "F.Paste")
			(net 454 "/DDR5 RDIMM/B.DQ23")
			(pinfunction "DQ23_B")
			(pintype "input")
		)
		(pad "277" smd rect
			(at 53.975 -2.301 270)
			(size 1.8 0.57)
			(layers "F.Cu" "F.Mask" "F.Paste")
			(net 1 "GND")
			(pinfunction "VSS")
			(pintype "passive")
		)
		(pad "278" smd rect
			(at 54.825 -2.301 270)
			(size 1.8 0.57)
			(layers "F.Cu" "F.Mask" "F.Paste")
			(net 455 "/DDR5 RDIMM/B.DQ26")
			(pinfunction "DQ26_B")
			(pintype "input")
		)
		(pad "279" smd rect
			(at 55.673 -2.301 270)
			(size 1.8 0.57)
			(layers "F.Cu" "F.Mask" "F.Paste")
			(net 1 "GND")
			(pinfunction "VSS")
			(pintype "passive")
		)
		(pad "280" smd rect
			(at 56.523 -2.301 270)
			(size 1.8 0.57)
			(layers "F.Cu" "F.Mask" "F.Paste")
			(net 456 "/DDR5 RDIMM/B.DQ27")
			(pinfunction "DQ27_B")
			(pintype "input")
		)
		(pad "281" smd rect
			(at 57.374 -2.301 270)
			(size 1.8 0.57)
			(layers "F.Cu" "F.Mask" "F.Paste")
			(net 1 "GND")
			(pinfunction "VSS")
			(pintype "passive")
		)
		(pad "282" smd rect
			(at 58.225 -2.301 270)
			(size 1.8 0.57)
			(layers "F.Cu" "F.Mask" "F.Paste")
			(net 596 "/DDR5 RDIMM/B.DQS8_N")
			(pinfunction "DQS8_B_C")
			(pintype "input")
		)
		(pad "283" smd rect
			(at 59.075 -2.301 270)
			(size 1.8 0.57)
			(layers "F.Cu" "F.Mask" "F.Paste")
			(net 597 "/DDR5 RDIMM/B.DQS8_P")
			(pinfunction "DQS8_B_T")
			(pintype "input")
		)
		(pad "284" smd rect
			(at 59.923 -2.301 270)
			(size 1.8 0.57)
			(layers "F.Cu" "F.Mask" "F.Paste")
			(net 1 "GND")
			(pinfunction "VSS")
			(pintype "passive")
		)
		(pad "285" smd rect
			(at 60.773 -2.301 270)
			(size 1.8 0.57)
			(layers "F.Cu" "F.Mask" "F.Paste")
			(net 475 "/DDR5 RDIMM/B.DQ30")
			(pinfunction "DQ30_B")
			(pintype "input")
		)
		(pad "286" smd rect
			(at 61.624 -2.301 270)
			(size 1.8 0.57)
			(layers "F.Cu" "F.Mask" "F.Paste")
			(net 1 "GND")
			(pinfunction "VSS")
			(pintype "passive")
		)
		(pad "287" smd rect
			(at 62.475 -2.301 270)
			(size 1.8 0.57)
			(layers "F.Cu" "F.Mask" "F.Paste")
			(net 476 "/DDR5 RDIMM/B.DQ31")
			(pinfunction "DQ31_B")
			(pintype "input")
		)
		(pad "288" smd rect
			(at 63.325 -2.301 270)
			(size 1.8 0.57)
			(layers "F.Cu" "F.Mask" "F.Paste")
			(net 1 "GND")
			(pinfunction "VSS")
			(pintype "passive")
		)
		(pad "S1" thru_hole oval
			(at -68.976 0 180)
			(size 1.875 3.75)
			(drill oval 1.25 2.53)
			(layers "*.Cu" "*.Mask")
			(remove_unused_layers no)
			(net 1 "GND")
			(pinfunction "SH")
			(pintype "passive")
		)
		(pad "S2" thru_hole oval
			(at 3.874 0 180)
			(size 1.875 3.75)
			(drill oval 1.25 2.53)
			(layers "*.Cu" "*.Mask")
			(remove_unused_layers no)
			(net 1 "GND")
			(pinfunction "SH")
			(pintype "passive")
		)
		(pad "S3" thru_hole oval
			(at 68.974 0 180)
			(size 1.875 3.75)
			(drill oval 1.25 2.53)
			(layers "*.Cu" "*.Mask")
			(remove_unused_layers no)
			(net 1 "GND")
			(pinfunction "SH")
			(pintype "passive")
		)
	)
)
